# T6G (Grand Teton) — schematic netlist excerpt (pin names and nets, part order shuffled) for the footprints in the layout excerpt that follows; sources: Cadence DE-HDL packaged netlist, KiCad conversion of 04192023_DAF0TMB3IC0_F0TG_MB_C_brd_V02_OCP.brd

C2566  Q_CAP  22UF 4V 20% X6S  pkg C0402  page 70 : A = PVDDCR_SOC_P0 ; B = GND
C1026  Q_CAP  22UF 4V 20% X6S  pkg C0402  page 312 : A = P0V9_CPU0_RT3_2A ; B = GND

(kicad_pcb
	(version 20260206)
	(generator "pcbnew")
	(generator_version "10.0")
	(general
		(thickness 1.6)
		(legacy_teardrops no)
	)
	(paper "A4")
	(title_block
		(title "04192023_DAF0TMB3IC0_F0TG_MB_C_brd_V02_OCP.brd")
		(comment 1 "Grand Teton / footprints 6204-6205 of 8354")
	)
	(layers
		(0 "F.Cu" signal "TOP")
		(4 "In1.Cu" signal "GND")
		(6 "In2.Cu" signal "IN1")
		(8 "In3.Cu" signal "GND1")
		(10 "In4.Cu" signal "IN2")
		(12 "In5.Cu" signal "GND2")
		(14 "In6.Cu" signal "IN3")
		(16 "In7.Cu" signal "GND3")
		(18 "In8.Cu" signal "VCC")
		(20 "In9.Cu" signal "VCC1")
		(22 "In10.Cu" signal "GND4")
		(24 "In11.Cu" signal "IN4")
		(26 "In12.Cu" signal "GND5")
		(28 "In13.Cu" signal "IN5")
		(30 "In14.Cu" signal "GND6")
		(32 "In15.Cu" signal "IN6")
		(34 "In16.Cu" signal "GND7")
		(2 "B.Cu" signal "BOTTOM")
		(9 "F.Adhes" user "F.Adhesive")
		(11 "B.Adhes" user "B.Adhesive")
		(13 "F.Paste" user "Package Geometry/Pastemask Top")
		(15 "B.Paste" user "Package Geometry/Pastemask Bottom")
		(5 "F.SilkS" user "Ref Des/Silkscreen Top")
		(7 "B.SilkS" user "Ref Des/Silkscreen Bottom")
		(1 "F.Mask" user "Board Geometry/Soldermask Top")
		(3 "B.Mask" user "Board Geometry/Soldermask Bottom")
		(17 "Dwgs.User" user "User.Drawings")
		(19 "Cmts.User" user "User.Comments")
		(21 "Eco1.User" user "User.Eco1")
		(23 "Eco2.User" user "User.Eco2")
		(25 "Edge.Cuts" user "Board Geometry/Outline")
		(27 "Margin" user)
		(31 "F.CrtYd" user "Package Geometry/Place Bound Top")
		(29 "B.CrtYd" user "Package Geometry/Place Bound Bottom")
		(35 "F.Fab" user "Ref Des/Assembly Top")
		(33 "B.Fab" user "Ref Des/Assembly Bottom")
	)
	(footprint ""
		(layer "B.Cu")
		(at 386.091176 -398.942052 90)
		(property "Reference" "C1026"
			(at 0 0 90)
			(layer "B.SilkS")
			(hide yes)
			(effects
				(font
					(size 1.27 1.27)
				)
				(justify mirror)
			)
		)
		(property "Value" ""
			(at 0 0 90)
			(layer "B.Fab")
			(effects
				(font
					(size 1.27 1.27)
				)
				(justify mirror)
			)
		)
		(duplicate_pad_numbers_are_jumpers no)
		(fp_line
			(start 0.7874 -0.4064)
			(end -0.7874 -0.4064)
			(stroke
				(width 0.1524)
				(type default)
			)
			(layer "B.SilkS")
		)
		(fp_line
			(start -0.7874 -0.4064)
			(end -0.7874 0.4064)
			(stroke
				(width 0.1524)
				(type default)
			)
			(layer "B.SilkS")
		)
		(fp_line
			(start 0.7874 0.4064)
			(end 0.7874 -0.4064)
			(stroke
				(width 0.1524)
				(type default)
			)
			(layer "B.SilkS")
		)
		(fp_line
			(start -0.7874 0.4064)
			(end 0.7874 0.4064)
			(stroke
				(width 0.1524)
				(type default)
			)
			(layer "B.SilkS")
		)
		(fp_line
			(start 0.67945 -0.305054)
			(end 0.12065 -0.305054)
			(stroke
				(width 0.1)
				(type default)
			)
			(layer "B.Fab")
		)
		(fp_line
			(start 0.12065 -0.305054)
			(end 0.12065 -0.2794)
			(stroke
				(width 0.1)
				(type default)
			)
			(layer "B.Fab")
		)
		(fp_line
			(start -0.12065 -0.3048)
			(end -0.67945 -0.3048)
			(stroke
				(width 0.1)
				(type default)
			)
			(layer "B.Fab")
		)
		(fp_line
			(start -0.67945 -0.3048)
			(end -0.67945 0.3048)
			(stroke
				(width 0.1)
				(type default)
			)
			(layer "B.Fab")
		)
		(fp_line
			(start 0.12065 -0.2794)
			(end -0.12065 -0.2794)
			(stroke
				(width 0.1)
				(type default)
			)
			(layer "B.Fab")
		)
		(fp_line
			(start -0.12065 -0.2794)
			(end -0.12065 -0.3048)
			(stroke
				(width 0.1)
				(type default)
			)
			(layer "B.Fab")
		)
		(fp_line
			(start 0.12065 0.2794)
			(end 0.12065 0.3048)
			(stroke
				(width 0.1)
				(type default)
			)
			(layer "B.Fab")
		)
		(fp_line
			(start -0.120396 0.2794)
			(end 0.12065 0.2794)
			(stroke
				(width 0.1)
				(type default)
			)
			(layer "B.Fab")
		)
		(fp_line
			(start 0.67945 0.3048)
			(end 0.67945 -0.305054)
			(stroke
				(width 0.1)
				(type default)
			)
			(layer "B.Fab")
		)
		(fp_line
			(start 0.12065 0.3048)
			(end 0.67945 0.3048)
			(stroke
				(width 0.1)
				(type default)
			)
			(layer "B.Fab")
		)
		(fp_line
			(start -0.120396 0.3048)
			(end -0.120396 0.2794)
			(stroke
				(width 0.1)
				(type default)
			)
			(layer "B.Fab")
		)
		(fp_line
			(start -0.67945 0.3048)
			(end -0.120396 0.3048)
			(stroke
				(width 0.1)
				(type default)
			)
			(layer "B.Fab")
		)
		(pad "1" smd circle
			(at 0.40005 0 270)
			(size 0 0)
			(layers "B.Cu" "B.Mask" "B.Paste")
			(net "P0V9_CPU0_RT3_2A")
		)
		(pad "2" smd circle
			(at -0.40005 0 270)
			(size 0 0)
			(layers "B.Cu" "B.Mask" "B.Paste")
			(net "GND")
		)
	)
	(footprint ""
		(layer "B.Cu")
		(at 365.836454 -250.89231)
		(property "Reference" "C2566"
			(at 0 0 0)
			(layer "B.SilkS")
			(hide yes)
			(effects
				(font
					(size 1.27 1.27)
				)
				(justify mirror)
			)
		)
		(property "Value" ""
			(at 0 0 0)
			(layer "B.Fab")
			(effects
				(font
					(size 1.27 1.27)
				)
				(justify mirror)
			)
		)
		(duplicate_pad_numbers_are_jumpers no)
		(fp_line
			(start -0.7874 -0.4064)
			(end -0.7874 0.4064)
			(stroke
				(width 0.1524)
				(type default)
			)
			(layer "B.SilkS")
		)
		(fp_line
			(start -0.7874 0.4064)
			(end 0.7874 0.4064)
			(stroke
				(width 0.1524)
				(type default)
			)
			(layer "B.SilkS")
		)
		(fp_line
			(start 0.7874 -0.4064)
			(end -0.7874 -0.4064)
			(stroke
				(width 0.1524)
				(type default)
			)
			(layer "B.SilkS")
		)
		(fp_line
			(start 0.7874 0.4064)
			(end 0.7874 -0.4064)
			(stroke
				(width 0.1524)
				(type default)
			)
			(layer "B.SilkS")
		)
		(fp_line
			(start -0.67945 -0.3048)
			(end -0.67945 0.3048)
			(stroke
				(width 0.1)
				(type default)
			)
			(layer "B.Fab")
		)
		(fp_line
			(start -0.67945 0.3048)
			(end -0.120396 0.3048)
			(stroke
				(width 0.1)
				(type default)
			)
			(layer "B.Fab")
		)
		(fp_line
			(start -0.12065 -0.3048)
			(end -0.67945 -0.3048)
			(stroke
				(width 0.1)
				(type default)
			)
			(layer "B.Fab")
		)
		(fp_line
			(start -0.12065 -0.2794)
			(end -0.12065 -0.3048)
			(stroke
				(width 0.1)
				(type default)
			)
			(layer "B.Fab")
		)
		(fp_line
			(start -0.120396 0.2794)
			(end 0.12065 0.2794)
			(stroke
				(width 0.1)
				(type default)
			)
			(layer "B.Fab")
		)
		(fp_line
			(start -0.120396 0.3048)
			(end -0.120396 0.2794)
			(stroke
				(width 0.1)
				(type default)
			)
			(layer "B.Fab")
		)
		(fp_line
			(start 0.12065 -0.305054)
			(end 0.12065 -0.2794)
			(stroke
				(width 0.1)
				(type default)
			)
			(layer "B.Fab")
		)
		(fp_line
			(start 0.12065 -0.2794)
			(end -0.12065 -0.2794)
			(stroke
				(width 0.1)
				(type default)
			)
			(layer "B.Fab")
		)
		(fp_line
			(start 0.12065 0.2794)
			(end 0.12065 0.3048)
			(stroke
				(width 0.1)
				(type default)
			)
			(layer "B.Fab")
		)
		(fp_line
			(start 0.12065 0.3048)
			(end 0.67945 0.3048)
			(stroke
				(width 0.1)
				(type default)
			)
			(layer "B.Fab")
		)
		(fp_line
			(start 0.67945 -0.305054)
			(end 0.12065 -0.305054)
			(stroke
				(width 0.1)
				(type default)
			)
			(layer "B.Fab")
		)
		(fp_line
			(start 0.67945 0.3048)
			(end 0.67945 -0.305054)
			(stroke
				(width 0.1)
				(type default)
			)
			(layer "B.Fab")
		)
		(pad "1" smd circle
			(at 0.40005 0 180)
			(size 0 0)
			(layers "B.Cu" "B.Mask" "B.Paste")
			(net "PVDDCR_SOC_P0")
		)
		(pad "2" smd circle
			(at -0.40005 0 180)
			(size 0 0)
			(layers "B.Cu" "B.Mask" "B.Paste")
			(net "GND")
		)
	)
)
